(kicad_pcb
	(version 20241229)
	(generator "pcbnew")
	(generator_version "9.0")
	(general
		(thickness 1.62)
		(legacy_teardrops no)
	)
	(paper "A4")
	(title_block
		(title "OCuLink to 10GbE adapter")
		(date "2026-02-23")
		(rev "1.1.0")
		(company "Antmicro Ltd")
		(comment 1 "www.antmicro.com")
		(comment 9 "footprints 413-418 of 510")
	)
	(layers
		(0 "F.Cu" signal)
		(4 "In1.Cu" signal)
		(6 "In2.Cu" signal)
		(8 "In3.Cu" signal)
		(10 "In4.Cu" signal)
		(12 "In5.Cu" signal)
		(14 "In6.Cu" signal)
		(2 "B.Cu" signal)
		(9 "F.Adhes" user "F.Adhesive")
		(11 "B.Adhes" user "B.Adhesive")
		(13 "F.Paste" user)
		(15 "B.Paste" user)
		(5 "F.SilkS" user "F.Silkscreen")
		(7 "B.SilkS" user "B.Silkscreen")
		(1 "F.Mask" user)
		(3 "B.Mask" user)
		(17 "Dwgs.User" user "User.Drawings")
		(19 "Cmts.User" user "User.Comments")
		(21 "Eco1.User" user "User.Eco1")
		(23 "Eco2.User" user "User.Eco2")
		(25 "Edge.Cuts" user)
		(27 "Margin" user)
		(31 "F.CrtYd" user "F.Courtyard")
		(29 "B.CrtYd" user "B.Courtyard")
		(35 "F.Fab" user)
		(33 "B.Fab" user)
	)
	(footprint "antmicro-footprints:R_0402_1005Metric"
		(layer "B.Cu")
		(at 96.88 110.95)
		(descr "Resistor SMD 0402")
		(tags "resistor SMD 0402")
		(property "Reference" "R112"
			(at -3.61 -0.34 0)
			(layer "B.SilkS")
			(effects
				(font
					(size 0.7 0.7)
					(thickness 0.15)
				)
				(justify right top mirror)
			)
		)
		(property "Value" "R_1k_0402"
			(at -1.011843 -1.772046 0)
			(layer "B.Fab")
			(hide yes)
			(effects
				(font
					(size 0.7 0.7)
					(thickness 0.15)
				)
				(justify right top mirror)
			)
		)
		(property "Datasheet" "https://www.bourns.com/docs/product-datasheets/cr.pdf"
			(at 0 0 0)
			(layer "B.Fab")
			(hide yes)
			(effects
				(font
					(size 1.27 1.27)
					(thickness 0.15)
				)
				(justify mirror)
			)
		)
		(property "Description" "SMD Chip Resistor, 1 kohm, ± 1%, 63 mW, 0402 [1005 Metric], Thick Film, General Purpose"
			(at 0 0 0)
			(layer "B.Fab")
			(hide yes)
			(effects
				(font
					(size 1.27 1.27)
					(thickness 0.15)
				)
				(justify mirror)
			)
		)
		(property "MPN" "CR0402-FX-1001GLF"
			(at 0 0 0)
			(unlocked yes)
			(layer "B.Fab")
			(hide yes)
			(effects
				(font
					(size 1 1)
					(thickness 0.15)
				)
				(justify mirror)
			)
		)
		(property "Manufacturer" "Bourns"
			(at 0 0 0)
			(unlocked yes)
			(layer "B.Fab")
			(hide yes)
			(effects
				(font
					(size 1 1)
					(thickness 0.15)
				)
				(justify mirror)
			)
		)
		(property "License" "Apache-2.0"
			(at 0 0 0)
			(unlocked yes)
			(layer "B.Fab")
			(hide yes)
			(effects
				(font
					(size 1 1)
					(thickness 0.15)
				)
				(justify mirror)
			)
		)
		(property "Author" "Antmicro"
			(at 0 0 0)
			(unlocked yes)
			(layer "B.Fab")
			(hide yes)
			(effects
				(font
					(size 1 1)
					(thickness 0.15)
				)
				(justify mirror)
			)
		)
		(property "Val" "1k"
			(at 0 0 0)
			(unlocked yes)
			(layer "B.Fab")
			(hide yes)
			(effects
				(font
					(size 1 1)
					(thickness 0.15)
				)
				(justify mirror)
			)
		)
		(property "Tolerance" "1%"
			(at 0 0 0)
			(unlocked yes)
			(layer "B.Fab")
			(hide yes)
			(effects
				(font
					(size 1 1)
					(thickness 0.15)
				)
				(justify mirror)
			)
		)
		(sheetname "/X710-AT2 Misc/")
		(sheetfile "x710-at2-mics.kicad_sch")
		(attr smd)
		(fp_rect
			(start -0.925 0.47)
			(end 0.925 -0.47)
			(stroke
				(width 0.05)
				(type default)
			)
			(fill no)
			(layer "B.CrtYd")
		)
		(fp_rect
			(start -0.5 0.25)
			(end 0.5 -0.25)
			(stroke
				(width 0.15)
				(type solid)
			)
			(fill no)
			(layer "B.Fab")
		)
		(pad "1" smd roundrect
			(at -0.48 0)
			(size 0.59 0.64)
			(layers "B.Cu" "B.Mask" "B.Paste")
			(roundrect_rratio 0.25)
			(net 287 "/X710-AT2 10GbE/~{P1_INT}")
			(pintype "passive")
		)
		(pad "2" smd roundrect
			(at 0.48 0)
			(size 0.59 0.64)
			(layers "B.Cu" "B.Mask" "B.Paste")
			(roundrect_rratio 0.25)
			(net 7 "+3V3")
			(pintype "passive")
		)
	)
	(footprint "antmicro-footprints:R_0402_1005Metric"
		(layer "B.Cu")
		(at 96.45 100.1)
		(descr "Resistor SMD 0402")
		(tags "resistor SMD 0402")
		(property "Reference" "R61"
			(at 0.9 -0.327778 0)
			(layer "B.SilkS")
			(effects
				(font
					(size 0.7 0.7)
					(thickness 0.15)
				)
				(justify right top mirror)
			)
		)
		(property "Value" "R_3k3_0402"
			(at -1.011843 -1.772046 0)
			(layer "B.Fab")
			(hide yes)
			(effects
				(font
					(size 0.7 0.7)
					(thickness 0.15)
				)
				(justify right top mirror)
			)
		)
		(property "Datasheet" "https://www.bourns.com/docs/product-datasheets/cr.pdf"
			(at 0 0 0)
			(layer "B.Fab")
			(hide yes)
			(effects
				(font
					(size 1.27 1.27)
					(thickness 0.15)
				)
				(justify mirror)
			)
		)
		(property "Description" "SMD Chip Resistor, 3.3 kohm, ± 1%, 63 mW, 0402 [1005 Metric], Thick Film, General Purpose"
			(at 0 0 0)
			(layer "B.Fab")
			(hide yes)
			(effects
				(font
					(size 1.27 1.27)
					(thickness 0.15)
				)
				(justify mirror)
			)
		)
		(property "MPN" "CR0402-FX-3301GLF"
			(at 0 0 0)
			(unlocked yes)
			(layer "B.Fab")
			(hide yes)
			(effects
				(font
					(size 1 1)
					(thickness 0.15)
				)
				(justify mirror)
			)
		)
		(property "Manufacturer" "Bourns"
			(at 0 0 0)
			(unlocked yes)
			(layer "B.Fab")
			(hide yes)
			(effects
				(font
					(size 1 1)
					(thickness 0.15)
				)
				(justify mirror)
			)
		)
		(property "License" "Apache-2.0"
			(at 0 0 0)
			(unlocked yes)
			(layer "B.Fab")
			(hide yes)
			(effects
				(font
					(size 1 1)
					(thickness 0.15)
				)
				(justify mirror)
			)
		)
		(property "Author" "Antmicro"
			(at 0 0 0)
			(unlocked yes)
			(layer "B.Fab")
			(hide yes)
			(effects
				(font
					(size 1 1)
					(thickness 0.15)
				)
				(justify mirror)
			)
		)
		(property "Val" "3k3"
			(at 0 0 0)
			(unlocked yes)
			(layer "B.Fab")
			(hide yes)
			(effects
				(font
					(size 1 1)
					(thickness 0.15)
				)
				(justify mirror)
			)
		)
		(property "Tolerance" "1%"
			(at 0 0 0)
			(unlocked yes)
			(layer "B.Fab")
			(hide yes)
			(effects
				(font
					(size 1 1)
					(thickness 0.15)
				)
				(justify mirror)
			)
		)
		(sheetname "/X710-AT2 10GbE/")
		(sheetfile "x710-at2-10gbe.kicad_sch")
		(attr smd)
		(fp_rect
			(start -0.925 0.47)
			(end 0.925 -0.47)
			(stroke
				(width 0.05)
				(type default)
			)
			(fill no)
			(layer "B.CrtYd")
		)
		(fp_rect
			(start -0.5 0.25)
			(end 0.5 -0.25)
			(stroke
				(width 0.15)
				(type solid)
			)
			(fill no)
			(layer "B.Fab")
		)
		(pad "1" smd roundrect
			(at -0.48 0)
			(size 0.59 0.64)
			(layers "B.Cu" "B.Mask" "B.Paste")
			(roundrect_rratio 0.25)
			(net 96 "/X710-AT2 10GbE/MDC2_SCL2")
			(pintype "passive")
		)
		(pad "2" smd roundrect
			(at 0.48 0)
			(size 0.59 0.64)
			(layers "B.Cu" "B.Mask" "B.Paste")
			(roundrect_rratio 0.25)
			(net 7 "+3V3")
			(pintype "passive")
		)
	)
	(footprint "antmicro-footprints:TP_SMD_1mm"
		(layer "B.Cu")
		(at 77.99 74.55 -90)
		(property "Reference" "TP30"
			(at -1.04 5.811898 90)
			(layer "B.SilkS")
			(effects
				(font
					(size 0.7 0.7)
					(thickness 0.15)
				)
				(justify left bottom mirror)
			)
		)
		(property "Value" "TP_1mm_SMD"
			(at 0 -1.4 90)
			(layer "B.Fab")
			(hide yes)
			(effects
				(font
					(size 0.7 0.7)
					(thickness 0.15)
				)
				(justify left bottom mirror)
			)
		)
		(property "Description" "Test point 1mm SMD"
			(at 0 0 90)
			(layer "B.Fab")
			(hide yes)
			(effects
				(font
					(size 1.27 1.27)
					(thickness 0.15)
				)
				(justify mirror)
			)
		)
		(property "MPN" ""
			(at 0 0 90)
			(unlocked yes)
			(layer "B.Fab")
			(hide yes)
			(effects
				(font
					(size 1 1)
					(thickness 0.15)
				)
				(justify mirror)
			)
		)
		(property "Manufacturer" ""
			(at 0 0 90)
			(unlocked yes)
			(layer "B.Fab")
			(hide yes)
			(effects
				(font
					(size 1 1)
					(thickness 0.15)
				)
				(justify mirror)
			)
		)
		(property "Author" "Antmicro"
			(at 0 0 90)
			(unlocked yes)
			(layer "B.Fab")
			(hide yes)
			(effects
				(font
					(size 1 1)
					(thickness 0.15)
				)
				(justify mirror)
			)
		)
		(property "License" "Apache-2.0"
			(at 0 0 90)
			(unlocked yes)
			(layer "B.Fab")
			(hide yes)
			(effects
				(font
					(size 1 1)
					(thickness 0.15)
				)
				(justify mirror)
			)
		)
		(sheetname "/Power/")
		(sheetfile "power.kicad_sch")
		(attr exclude_from_pos_files exclude_from_bom)
		(fp_circle
			(center 0 0)
			(end 0.6 0)
			(stroke
				(width 0.05)
				(type default)
			)
			(fill no)
			(layer "B.CrtYd")
		)
		(pad "1" smd circle
			(at 0 0 270)
			(size 1 1)
			(layers "B.Cu" "B.Mask")
			(net 7 "+3V3")
			(pinfunction "1")
			(pintype "passive")
		)
	)
	(footprint "antmicro-footprints:C_0805_2012Metric"
		(layer "B.Cu")
		(at 103.95 134.7 180)
		(descr "Capacitor SMD 0805")
		(tags "capacitor SMD 0805")
		(property "Reference" "C63"
			(at -1.2 -1.05 0)
			(layer "B.SilkS")
			(effects
				(font
					(size 0.7 0.7)
					(thickness 0.15)
				)
				(justify left top mirror)
			)
		)
		(property "Value" "C_100u_0805"
			(at -2.055717 -1.963153 0)
			(layer "B.Fab")
			(hide yes)
			(effects
				(font
					(size 0.7 0.7)
					(thickness 0.15)
				)
				(justify left bottom mirror)
			)
		)
		(property "Datasheet" "https://www.murata.com/products/productdetail?partno=GRM21BR60J107ME15%23"
			(at 0 0 0)
			(layer "B.Fab")
			(hide yes)
			(effects
				(font
					(size 1.27 1.27)
					(thickness 0.15)
				)
				(justify mirror)
			)
		)
		(property "Description" "SMD Multilayer Ceramic Capacitor, 100 µF, 6.3 V, 0805 [2012 Metric], ± 20%, X5R, GRM Series"
			(at 0 0 0)
			(layer "B.Fab")
			(hide yes)
			(effects
				(font
					(size 1.27 1.27)
					(thickness 0.15)
				)
				(justify mirror)
			)
		)
		(property "MPN" "GRM21BR60J107ME15L"
			(at 0 0 180)
			(unlocked yes)
			(layer "B.Fab")
			(hide yes)
			(effects
				(font
					(size 1 1)
					(thickness 0.15)
				)
				(justify mirror)
			)
		)
		(property "Manufacturer" "Murata"
			(at 0 0 180)
			(unlocked yes)
			(layer "B.Fab")
			(hide yes)
			(effects
				(font
					(size 1 1)
					(thickness 0.15)
				)
				(justify mirror)
			)
		)
		(property "License" "Apache-2.0"
			(at 0 0 180)
			(unlocked yes)
			(layer "B.Fab")
			(hide yes)
			(effects
				(font
					(size 1 1)
					(thickness 0.15)
				)
				(justify mirror)
			)
		)
		(property "Author" "Antmicro"
			(at 0 0 180)
			(unlocked yes)
			(layer "B.Fab")
			(hide yes)
			(effects
				(font
					(size 1 1)
					(thickness 0.15)
				)
				(justify mirror)
			)
		)
		(property "Val" "100u"
			(at 0 0 180)
			(unlocked yes)
			(layer "B.Fab")
			(hide yes)
			(effects
				(font
					(size 1 1)
					(thickness 0.15)
				)
				(justify mirror)
			)
		)
		(property "Voltage" ""
			(at 0 0 180)
			(unlocked yes)
			(layer "B.Fab")
			(hide yes)
			(effects
				(font
					(size 1 1)
					(thickness 0.15)
				)
				(justify mirror)
			)
		)
		(property "Dielectric" ""
			(at 0 0 180)
			(unlocked yes)
			(layer "B.Fab")
			(hide yes)
			(effects
				(font
					(size 1 1)
					(thickness 0.15)
				)
				(justify mirror)
			)
		)
		(property "Public" "False"
			(at 0 0 180)
			(unlocked yes)
			(layer "B.Fab")
			(hide yes)
			(effects
				(font
					(size 1 1)
					(thickness 0.15)
				)
				(justify mirror)
			)
		)
		(sheetname "/2xRJ45/")
		(sheetfile "2xrj45.kicad_sch")
		(attr smd)
		(fp_line
			(start -0.3 0.7)
			(end 0.3 0.7)
			(stroke
				(width 0.15)
				(type solid)
			)
			(layer "B.SilkS")
		)
		(fp_line
			(start -0.3 -0.7)
			(end 0.3 -0.7)
			(stroke
				(width 0.15)
				(type solid)
			)
			(layer "B.SilkS")
		)
		(fp_rect
			(start 1.95 0.9)
			(end -1.95 -0.9)
			(stroke
				(width 0.05)
				(type default)
			)
			(fill no)
			(layer "B.CrtYd")
		)
		(fp_rect
			(start -0.95 0.675)
			(end 0.95 -0.675)
			(stroke
				(width 0.15)
				(type solid)
			)
			(fill no)
			(layer "B.Fab")
		)
		(pad "1" smd roundrect
			(at -1.1 0 180)
			(size 1.2 1.3)
			(layers "B.Cu" "B.Mask" "B.Paste")
			(roundrect_rratio 0.25)
			(net 28 "GND")
			(pintype "passive")
		)
		(pad "2" smd roundrect
			(at 1.1 0 180)
			(size 1.2 1.3)
			(layers "B.Cu" "B.Mask" "B.Paste")
			(roundrect_rratio 0.25)
			(net 300 "/2xRJ45/P1_CT")
			(pintype "passive")
		)
	)
	(footprint "antmicro-footprints:R_0402_1005Metric"
		(layer "B.Cu")
		(at 76.8 102.8)
		(descr "Resistor SMD 0402")
		(tags "resistor SMD 0402")
		(property "Reference" "R57"
			(at -2.9 -0.85 0)
			(layer "B.SilkS")
			(effects
				(font
					(size 0.7 0.7)
					(thickness 0.15)
				)
				(justify right top mirror)
			)
		)
		(property "Value" "R_4k53_0402"
			(at -1.011843 -1.772046 0)
			(layer "B.Fab")
			(hide yes)
			(effects
				(font
					(size 0.7 0.7)
					(thickness 0.15)
				)
				(justify right top mirror)
			)
		)
		(property "Datasheet" "https://industrial.panasonic.com/cdbs/www-data/pdf/RDM0000/AOA0000C307.pdf"
			(at 0 0 0)
			(layer "B.Fab")
			(hide yes)
			(effects
				(font
					(size 1.27 1.27)
					(thickness 0.15)
				)
				(justify mirror)
			)
		)
		(property "Description" "SMD Chip Resistor, 4.53 kohm, ± 0.1%, 62.5 mW, 0402 [1005 Metric], Automotive AEC-Q200 Thin Film"
			(at 0 0 0)
			(layer "B.Fab")
			(hide yes)
			(effects
				(font
					(size 1.27 1.27)
					(thickness 0.15)
				)
				(justify mirror)
			)
		)
		(property "MPN" "ERA-2AEB4531X"
			(at 0 0 0)
			(unlocked yes)
			(layer "B.Fab")
			(hide yes)
			(effects
				(font
					(size 1 1)
					(thickness 0.15)
				)
				(justify mirror)
			)
		)
		(property "Manufacturer" "Panasonic"
			(at 0 0 0)
			(unlocked yes)
			(layer "B.Fab")
			(hide yes)
			(effects
				(font
					(size 1 1)
					(thickness 0.15)
				)
				(justify mirror)
			)
		)
		(property "License" "Apache-2.0"
			(at 0 0 0)
			(unlocked yes)
			(layer "B.Fab")
			(hide yes)
			(effects
				(font
					(size 1 1)
					(thickness 0.15)
				)
				(justify mirror)
			)
		)
		(property "Author" "Antmicro"
			(at 0 0 0)
			(unlocked yes)
			(layer "B.Fab")
			(hide yes)
			(effects
				(font
					(size 1 1)
					(thickness 0.15)
				)
				(justify mirror)
			)
		)
		(property "Val" "4k53"
			(at 0 0 0)
			(unlocked yes)
			(layer "B.Fab")
			(hide yes)
			(effects
				(font
					(size 1 1)
					(thickness 0.15)
				)
				(justify mirror)
			)
		)
		(property "Tolerance" "0.1%"
			(at 0 0 0)
			(unlocked yes)
			(layer "B.Fab")
			(hide yes)
			(effects
				(font
					(size 1 1)
					(thickness 0.15)
				)
				(justify mirror)
			)
		)
		(sheetname "/X710-AT2 10GbE/")
		(sheetfile "x710-at2-10gbe.kicad_sch")
		(attr smd)
		(fp_rect
			(start -0.925 0.47)
			(end 0.925 -0.47)
			(stroke
				(width 0.05)
				(type default)
			)
			(fill no)
			(layer "B.CrtYd")
		)
		(fp_rect
			(start -0.5 0.25)
			(end 0.5 -0.25)
			(stroke
				(width 0.15)
				(type solid)
			)
			(fill no)
			(layer "B.Fab")
		)
		(pad "1" smd roundrect
			(at -0.48 0)
			(size 0.59 0.64)
			(layers "B.Cu" "B.Mask" "B.Paste")
			(roundrect_rratio 0.25)
			(net 28 "GND")
			(pintype "passive")
		)
		(pad "2" smd roundrect
			(at 0.48 0)
			(size 0.59 0.64)
			(layers "B.Cu" "B.Mask" "B.Paste")
			(roundrect_rratio 0.25)
			(net 83 "/X710-AT2 10GbE/RESCAL_RES_P")
			(pintype "passive")
		)
	)
	(footprint "antmicro-footprints:C_0603_1608Metric"
		(layer "B.Cu")
		(at 76.5 99.2 180)
		(descr "Capacitor SMD 0603")
		(tags "capacitor 0603")
		(property "Reference" "C99"
			(at -1.09 0.71 0)
			(layer "B.SilkS")
			(effects
				(font
					(size 0.7 0.7)
					(thickness 0.15)
				)
				(justify left bottom mirror)
			)
		)
		(property "Value" "C_10u_10V_X7R_0603"
			(at -1.42757 -1.770288 0)
			(layer "B.Fab")
			(hide yes)
			(effects
				(font
					(size 0.7 0.7)
					(thickness 0.15)
				)
				(justify left bottom mirror)
			)
		)
		(property "Datasheet" "https://www.murata.com/products/productdetail?partno=GRM188Z71A106KA73%23"
			(at 0 0 0)
			(layer "B.Fab")
			(hide yes)
			(effects
				(font
					(size 1.27 1.27)
					(thickness 0.15)
				)
				(justify mirror)
			)
		)
		(property "Description" "SMD Multilayer Ceramic Capacitor,  10µF, 10V, 0603, ±10%, X7R"
			(at 0 0 0)
			(layer "B.Fab")
			(hide yes)
			(effects
				(font
					(size 1.27 1.27)
					(thickness 0.15)
				)
				(justify mirror)
			)
		)
		(property "MPN" "GRM188Z71A106KA73D"
			(at 0 0 180)
			(unlocked yes)
			(layer "B.Fab")
			(hide yes)
			(effects
				(font
					(size 1 1)
					(thickness 0.15)
				)
				(justify mirror)
			)
		)
		(property "Val" "10u"
			(at 0 0 180)
			(unlocked yes)
			(layer "B.Fab")
			(hide yes)
			(effects
				(font
					(size 1 1)
					(thickness 0.15)
				)
				(justify mirror)
			)
		)
		(property "Voltage" "10V"
			(at 0 0 180)
			(unlocked yes)
			(layer "B.Fab")
			(hide yes)
			(effects
				(font
					(size 1 1)
					(thickness 0.15)
				)
				(justify mirror)
			)
		)
		(property "Dielectric" "X7R"
			(at 0 0 180)
			(unlocked yes)
			(layer "B.Fab")
			(hide yes)
			(effects
				(font
					(size 1 1)
					(thickness 0.15)
				)
				(justify mirror)
			)
		)
		(property "Manufacturer" "Murata"
			(at 0 0 180)
			(unlocked yes)
			(layer "B.Fab")
			(hide yes)
			(effects
				(font
					(size 1 1)
					(thickness 0.15)
				)
				(justify mirror)
			)
		)
		(property "License" "Apache-2.0"
			(at 0 0 180)
			(unlocked yes)
			(layer "B.Fab")
			(hide yes)
			(effects
				(font
					(size 1 1)
					(thickness 0.15)
				)
				(justify mirror)
			)
		)
		(property "Author" "Antmicro"
			(at 0 0 180)
			(unlocked yes)
			(layer "B.Fab")
			(hide yes)
			(effects
				(font
					(size 1 1)
					(thickness 0.15)
				)
				(justify mirror)
			)
		)
		(sheetname "/X710-AT2 power/")
		(sheetfile "x710-at2-power.kicad_sch")
		(attr smd)
		(fp_line
			(start -0.15 0.4)
			(end 0.15 0.4)
			(stroke
				(width 0.15)
				(type solid)
			)
			(layer "B.SilkS")
		)
		(fp_line
			(start -0.15 -0.4)
			(end 0.15 -0.4)
			(stroke
				(width 0.15)
				(type solid)
			)
			(layer "B.SilkS")
		)
		(fp_rect
			(start -1.25 0.65)
			(end 1.25 -0.65)
			(stroke
				(width 0.05)
				(type solid)
			)
			(fill no)
			(layer "B.CrtYd")
		)
		(fp_rect
			(start -0.8 0.4)
			(end 0.8 -0.4)
			(stroke
				(width 0.15)
				(type solid)
			)
			(fill no)
			(layer "B.Fab")
		)
		(pad "1" smd roundrect
			(at -0.7 0 180)
			(size 0.8 1)
			(layers "B.Cu" "B.Mask" "B.Paste")
			(roundrect_rratio 0.2)
			(net 28 "GND")
			(pintype "passive")
		)
		(pad "2" smd roundrect
			(at 0.7 0 180)
			(size 0.8 1)
			(layers "B.Cu" "B.Mask" "B.Paste")
			(roundrect_rratio 0.2)
			(net 18 "+1V88")
			(pintype "passive")
		)
	)
)
